(kicad_pcb
	(version 20241229)
	(generator "pcbnew")
	(generator_version "9.0")
	(general
		(thickness 1.711)
		(legacy_teardrops no)
	)
	(paper "A4")
	(title_block
		(title "Antmicro Baseboard for Jetson AGX Thor")
		(date "2026-02-18")
		(rev "1.1.0")
		(company "Antmicro Ltd")
		(comment 1 "www.antmicro.com")
		(comment 9 "footprints 390-394 of 1170")
	)
	(layers
		(0 "F.Cu" signal)
		(4 "In1.Cu" signal)
		(6 "In2.Cu" signal)
		(8 "In3.Cu" signal)
		(10 "In4.Cu" jumper)
		(12 "In5.Cu" signal)
		(14 "In6.Cu" signal)
		(16 "In7.Cu" signal)
		(18 "In8.Cu" signal)
		(2 "B.Cu" signal)
		(9 "F.Adhes" user "F.Adhesive")
		(11 "B.Adhes" user "B.Adhesive")
		(13 "F.Paste" user)
		(15 "B.Paste" user)
		(5 "F.SilkS" user "F.Silkscreen")
		(7 "B.SilkS" user "B.Silkscreen")
		(1 "F.Mask" user)
		(3 "B.Mask" user)
		(17 "Dwgs.User" user "User.Drawings")
		(19 "Cmts.User" user "User.Comments")
		(21 "Eco1.User" user "User.Eco1")
		(23 "Eco2.User" user "User.Eco2")
		(25 "Edge.Cuts" user)
		(27 "Margin" user)
		(31 "F.CrtYd" user "F.Courtyard")
		(29 "B.CrtYd" user "B.Courtyard")
		(35 "F.Fab" user)
		(33 "B.Fab" user)
	)
	(footprint "antmicro-footprints:C_0805_2012Metric"
		(layer "F.Cu")
		(at 175 99.81 90)
		(descr "Capacitor SMD 0805")
		(tags "capacitor SMD 0805")
		(property "Reference" "C248"
			(at -4.565 0.4 90)
			(layer "F.SilkS")
			(effects
				(font
					(size 0.7 0.7)
					(thickness 0.15)
				)
				(justify left bottom)
			)
		)
		(property "Value" "C_22u_25V_0805"
			(at -2.055717 1.963152 90)
			(layer "F.Fab")
			(effects
				(font
					(size 0.7 0.7)
					(thickness 0.15)
				)
				(justify left bottom)
			)
		)
		(property "Datasheet" "https://product.samsungsem.com/mlcc/CL21A226MAYNNN.do"
			(at 0 0 90)
			(layer "F.Fab")
			(hide yes)
			(effects
				(font
					(size 1.27 1.27)
					(thickness 0.15)
				)
			)
		)
		(property "Description" "SMT Multilayer Ceramic Capacitor, 22uF, +/-20%, 25V, X5R, 0805 [2012 Metric]"
			(at 0 0 90)
			(layer "F.Fab")
			(hide yes)
			(effects
				(font
					(size 1.27 1.27)
					(thickness 0.15)
				)
			)
		)
		(property "MPN" "CL21A226MAYNNNE"
			(at 0 0 90)
			(unlocked yes)
			(layer "F.Fab")
			(hide yes)
			(effects
				(font
					(size 1 1)
					(thickness 0.15)
				)
			)
		)
		(property "Manufacturer" "Samsung Electro-Mechanics"
			(at 0 0 90)
			(unlocked yes)
			(layer "F.Fab")
			(hide yes)
			(effects
				(font
					(size 1 1)
					(thickness 0.15)
				)
			)
		)
		(property "License" "Apache-2.0"
			(at 0 0 90)
			(unlocked yes)
			(layer "F.Fab")
			(hide yes)
			(effects
				(font
					(size 1 1)
					(thickness 0.15)
				)
			)
		)
		(property "Author" "Antmicro"
			(at 0 0 90)
			(unlocked yes)
			(layer "F.Fab")
			(hide yes)
			(effects
				(font
					(size 1 1)
					(thickness 0.15)
				)
			)
		)
		(property "Val" "22u"
			(at 0 0 90)
			(unlocked yes)
			(layer "F.Fab")
			(hide yes)
			(effects
				(font
					(size 1 1)
					(thickness 0.15)
				)
			)
		)
		(property "Voltage" "25V"
			(at 0 0 90)
			(unlocked yes)
			(layer "F.Fab")
			(hide yes)
			(effects
				(font
					(size 1 1)
					(thickness 0.15)
				)
			)
		)
		(property "Dielectric" "X5R"
			(at 0 0 90)
			(unlocked yes)
			(layer "F.Fab")
			(hide yes)
			(effects
				(font
					(size 1 1)
					(thickness 0.15)
				)
			)
		)
		(property "Public" "False"
			(at 0 0 90)
			(unlocked yes)
			(layer "F.Fab")
			(hide yes)
			(effects
				(font
					(size 1 1)
					(thickness 0.15)
				)
			)
		)
		(component_classes
			(class "DCDC_SOM")
		)
		(sheetname "/DCDC/")
		(sheetfile "dcdc.kicad_sch")
		(attr smd)
		(fp_line
			(start -0.3 -0.7)
			(end 0.3 -0.7)
			(stroke
				(width 0.15)
				(type solid)
			)
			(layer "F.SilkS")
		)
		(fp_line
			(start -0.3 0.7)
			(end 0.3 0.7)
			(stroke
				(width 0.15)
				(type solid)
			)
			(layer "F.SilkS")
		)
		(fp_rect
			(start 1.95 -0.9)
			(end -1.95 0.9)
			(stroke
				(width 0.05)
				(type default)
			)
			(fill no)
			(layer "F.CrtYd")
		)
		(fp_rect
			(start -0.95 -0.675)
			(end 0.95 0.675)
			(stroke
				(width 0.15)
				(type solid)
			)
			(fill no)
			(layer "F.Fab")
		)
		(fp_text user "License: Apache-2.0"
			(at -1.9 4.947 90)
			(layer "F.Fab")
			(effects
				(font
					(size 0.7 0.7)
					(thickness 0.15)
				)
				(justify left bottom)
			)
		)
		(fp_text user "Author: Antmicro"
			(at -1.9 5.947 90)
			(layer "F.Fab")
			(effects
				(font
					(size 0.7 0.7)
					(thickness 0.15)
				)
				(justify left bottom)
			)
		)
		(fp_text user "${REFERENCE}"
			(at -1.9 3.947 90)
			(layer "F.Fab")
			(effects
				(font
					(size 0.7 0.7)
					(thickness 0.15)
				)
				(justify left bottom)
			)
		)
		(pad "1" smd roundrect
			(at -1.1 0 90)
			(size 1.2 1.3)
			(layers "F.Cu" "F.Mask" "F.Paste")
			(roundrect_rratio 0.25)
			(net 1 "GND")
			(pintype "passive")
		)
		(pad "2" smd roundrect
			(at 1.1 0 90)
			(size 1.2 1.3)
			(layers "F.Cu" "F.Mask" "F.Paste")
			(roundrect_rratio 0.25)
			(net 903 "/DCDC/16V_OUT")
			(pintype "passive")
		)
	)
	(footprint "antmicro-footprints:R_0402_1005Metric"
		(layer "F.Cu")
		(at 87.35 145.65 180)
		(descr "Resistor SMD 0402")
		(tags "resistor SMD 0402")
		(property "Reference" "R11"
			(at -1.15 1.35 0)
			(layer "F.SilkS")
			(effects
				(font
					(size 0.7 0.7)
					(thickness 0.15)
				)
				(justify right top)
			)
		)
		(property "Value" "R_100k_0402"
			(at -1.011843 1.772046 0)
			(layer "F.Fab")
			(effects
				(font
					(size 0.7 0.7)
					(thickness 0.15)
				)
				(justify right top)
			)
		)
		(property "Datasheet" "https://www.bourns.com/docs/product-datasheets/cr.pdf"
			(at 0 0 0)
			(layer "F.Fab")
			(hide yes)
			(effects
				(font
					(size 1.27 1.27)
					(thickness 0.15)
				)
			)
		)
		(property "Description" "SMD Chip Resistor, 100 kohm, ± 1%, 62.5 mW, 0402 [1005 Metric], Thick Film, General Purpose"
			(at 0 0 0)
			(layer "F.Fab")
			(hide yes)
			(effects
				(font
					(size 1.27 1.27)
					(thickness 0.15)
				)
			)
		)
		(property "MPN" "CR0402-FX-1003GLF"
			(at 0 0 180)
			(unlocked yes)
			(layer "F.Fab")
			(hide yes)
			(effects
				(font
					(size 1 1)
					(thickness 0.15)
				)
			)
		)
		(property "Manufacturer" "Bourns"
			(at 0 0 180)
			(unlocked yes)
			(layer "F.Fab")
			(hide yes)
			(effects
				(font
					(size 1 1)
					(thickness 0.15)
				)
			)
		)
		(property "License" "Apache-2.0"
			(at 0 0 180)
			(unlocked yes)
			(layer "F.Fab")
			(hide yes)
			(effects
				(font
					(size 1 1)
					(thickness 0.15)
				)
			)
		)
		(property "Author" "Antmicro"
			(at 0 0 180)
			(unlocked yes)
			(layer "F.Fab")
			(hide yes)
			(effects
				(font
					(size 1 1)
					(thickness 0.15)
				)
			)
		)
		(property "Val" "100k"
			(at 0 0 180)
			(unlocked yes)
			(layer "F.Fab")
			(hide yes)
			(effects
				(font
					(size 1 1)
					(thickness 0.15)
				)
			)
		)
		(property "Tolerance" "1%"
			(at 0 0 180)
			(unlocked yes)
			(layer "F.Fab")
			(hide yes)
			(effects
				(font
					(size 1 1)
					(thickness 0.15)
				)
			)
		)
		(sheetname "/SoM_IO2/")
		(sheetfile "som_io2.kicad_sch")
		(attr smd)
		(fp_poly
			(pts
				(xy -0.925 -0.47) (xy -0.925 0.47) (xy 0.925 0.47) (xy 0.925 -0.47)
			)
			(stroke
				(width 0.05)
				(type default)
			)
			(fill no)
			(layer "F.CrtYd")
		)
		(fp_poly
			(pts
				(xy -0.5 -0.25) (xy -0.5 0.25) (xy 0.5 0.25) (xy 0.5 -0.25)
			)
			(stroke
				(width 0.15)
				(type solid)
			)
			(fill no)
			(layer "F.Fab")
		)
		(fp_text user "${REFERENCE}"
			(at -0.95 3.168 0)
			(layer "F.Fab")
			(effects
				(font
					(size 0.7 0.7)
					(thickness 0.15)
				)
				(justify right top)
			)
		)
		(fp_text user "License: Apache-2.0"
			(at -0.949999 5.169 0)
			(layer "F.Fab")
			(effects
				(font
					(size 0.7 0.7)
					(thickness 0.15)
				)
				(justify right top)
			)
		)
		(fp_text user "Author: Antmicro"
			(at -0.95 4.169 0)
			(layer "F.Fab")
			(effects
				(font
					(size 0.7 0.7)
					(thickness 0.15)
				)
				(justify right top)
			)
		)
		(pad "1" smd roundrect
			(at -0.48 0 180)
			(size 0.59 0.64)
			(layers "F.Cu" "F.Mask" "F.Paste")
			(roundrect_rratio 0.25)
			(net 2 "+3V3")
			(pintype "passive")
		)
		(pad "2" smd roundrect
			(at 0.48 0 180)
			(size 0.59 0.64)
			(layers "F.Cu" "F.Mask" "F.Paste")
			(roundrect_rratio 0.25)
			(net 893 "Net-(Y1-EN)")
			(pintype "passive")
		)
	)
	(footprint "antmicro-footprints:C_0402_1005Metric"
		(layer "F.Cu")
		(at 193.126 148.1 180)
		(descr "Capacitor SMD 0402")
		(tags "capacitor SMD 0402")
		(property "Reference" "C58"
			(at 3.1 -0.5 180)
			(layer "F.SilkS")
			(effects
				(font
					(size 0.7 0.7)
					(thickness 0.15)
				)
				(justify left bottom)
			)
		)
		(property "Value" "C_100n_0402"
			(at -1.022927 2.155213 180)
			(layer "F.Fab")
			(effects
				(font
					(size 0.7 0.7)
					(thickness 0.15)
				)
				(justify left bottom)
			)
		)
		(property "Datasheet" "https://www.murata.com/products/productdetail?partno=GRM155R61H104KE14%23"
			(at 0 0 180)
			(layer "F.Fab")
			(hide yes)
			(effects
				(font
					(size 1.27 1.27)
					(thickness 0.15)
				)
			)
		)
		(property "Description" "SMD Multilayer Ceramic Capacitor, 0.1 µF, 50 V, 0402 [1005 Metric], ± 10%, X5R, GRM Series"
			(at 0 0 180)
			(layer "F.Fab")
			(hide yes)
			(effects
				(font
					(size 1.27 1.27)
					(thickness 0.15)
				)
			)
		)
		(property "Manufacturer" "Murata"
			(at 0 0 180)
			(unlocked yes)
			(layer "F.Fab")
			(hide yes)
			(effects
				(font
					(size 1 1)
					(thickness 0.15)
				)
			)
		)
		(property "MPN" "GRM155R61H104KE14D"
			(at 0 0 180)
			(unlocked yes)
			(layer "F.Fab")
			(hide yes)
			(effects
				(font
					(size 1 1)
					(thickness 0.15)
				)
			)
		)
		(property "Val" "100n"
			(at 0 0 180)
			(unlocked yes)
			(layer "F.Fab")
			(hide yes)
			(effects
				(font
					(size 1 1)
					(thickness 0.15)
				)
			)
		)
		(property "License" "Apache-2.0"
			(at 0 0 180)
			(unlocked yes)
			(layer "F.Fab")
			(hide yes)
			(effects
				(font
					(size 1 1)
					(thickness 0.15)
				)
			)
		)
		(property "Author" "Antmicro"
			(at 0 0 180)
			(unlocked yes)
			(layer "F.Fab")
			(hide yes)
			(effects
				(font
					(size 1 1)
					(thickness 0.15)
				)
			)
		)
		(property "Voltage" "50V"
			(at 0 0 180)
			(unlocked yes)
			(layer "F.Fab")
			(hide yes)
			(effects
				(font
					(size 1 1)
					(thickness 0.15)
				)
			)
		)
		(property "Dielectric" "X5R"
			(at 0 0 180)
			(unlocked yes)
			(layer "F.Fab")
			(hide yes)
			(effects
				(font
					(size 1 1)
					(thickness 0.15)
				)
			)
		)
		(property "Public" "False"
			(at 0 0 180)
			(unlocked yes)
			(layer "F.Fab")
			(hide yes)
			(effects
				(font
					(size 1 1)
					(thickness 0.15)
				)
			)
		)
		(sheetname "/SFP/")
		(sheetfile "sfp.kicad_sch")
		(attr smd)
		(fp_rect
			(start -0.925 -0.47)
			(end 0.925 0.47)
			(stroke
				(width 0.05)
				(type default)
			)
			(fill no)
			(layer "F.CrtYd")
		)
		(fp_line
			(start 0.504 0.248)
			(end -0.494 0.248)
			(stroke
				(width 0.15)
				(type solid)
			)
			(layer "F.Fab")
		)
		(fp_line
			(start 0.504 -0.25)
			(end 0.504 0.248)
			(stroke
				(width 0.15)
				(type solid)
			)
			(layer "F.Fab")
		)
		(fp_line
			(start -0.494 0.248)
			(end -0.494 -0.25)
			(stroke
				(width 0.15)
				(type solid)
			)
			(layer "F.Fab")
		)
		(fp_line
			(start -0.494 -0.25)
			(end 0.504 -0.25)
			(stroke
				(width 0.15)
				(type solid)
			)
			(layer "F.Fab")
		)
		(fp_text user "License: Apache-2.0"
			(at -0.939 5.799 180)
			(layer "F.Fab")
			(effects
				(font
					(size 0.7 0.7)
					(thickness 0.15)
				)
				(justify left bottom)
			)
		)
		(fp_text user "Author: Antmicro"
			(at -0.939 3.399 180)
			(layer "F.Fab")
			(effects
				(font
					(size 0.7 0.7)
					(thickness 0.15)
				)
				(justify left bottom)
			)
		)
		(fp_text user "${REFERENCE}"
			(at -0.939 4.599 180)
			(layer "F.Fab")
			(effects
				(font
					(size 0.7 0.7)
					(thickness 0.15)
				)
				(justify left bottom)
			)
		)
		(pad "1" smd roundrect
			(at -0.48 0 180)
			(size 0.59 0.64)
			(layers "F.Cu" "F.Mask" "F.Paste")
			(roundrect_rratio 0.25)
			(net 22 "/SFP/SFI_CONN_TX_N")
			(pintype "passive")
		)
		(pad "2" smd roundrect
			(at 0.48 0 180)
			(size 0.59 0.64)
			(layers "F.Cu" "F.Mask" "F.Paste")
			(roundrect_rratio 0.25)
			(net 132 "/SFP/SFI.TX-")
			(pintype "passive")
		)
	)
	(footprint "antmicro-footprints:R_0402_1005Metric"
		(layer "F.Cu")
		(at 181.513471 124.197356 -90)
		(descr "Resistor SMD 0402")
		(tags "resistor SMD 0402")
		(property "Reference" "R43"
			(at -6.297356 -3.086529 90)
			(layer "F.SilkS")
			(effects
				(font
					(size 0.7 0.7)
					(thickness 0.15)
				)
				(justify right top)
			)
		)
		(property "Value" "R_200k_0402"
			(at -1.011843 1.772047 90)
			(layer "F.Fab")
			(effects
				(font
					(size 0.7 0.7)
					(thickness 0.15)
				)
				(justify right top)
			)
		)
		(property "Datasheet" "https://www.bourns.com/docs/product-datasheets/cr.pdf"
			(at 0 0 90)
			(layer "F.Fab")
			(hide yes)
			(effects
				(font
					(size 1.27 1.27)
					(thickness 0.15)
				)
			)
		)
		(property "Description" "SMD Chip Resistor, 200 kohm, ± 1%, 62.5 mW, 0402 [1005 Metric], Thick Film, General Purpose"
			(at 0 0 90)
			(layer "F.Fab")
			(hide yes)
			(effects
				(font
					(size 1.27 1.27)
					(thickness 0.15)
				)
			)
		)
		(property "MPN" "CR0402-FX-2003GLF"
			(at 0 0 270)
			(unlocked yes)
			(layer "F.Fab")
			(hide yes)
			(effects
				(font
					(size 1 1)
					(thickness 0.15)
				)
			)
		)
		(property "Manufacturer" "Bourns"
			(at 0 0 270)
			(unlocked yes)
			(layer "F.Fab")
			(hide yes)
			(effects
				(font
					(size 1 1)
					(thickness 0.15)
				)
			)
		)
		(property "License" "Apache-2.0"
			(at 0 0 270)
			(unlocked yes)
			(layer "F.Fab")
			(hide yes)
			(effects
				(font
					(size 1 1)
					(thickness 0.15)
				)
			)
		)
		(property "Author" "Antmicro"
			(at 0 0 270)
			(unlocked yes)
			(layer "F.Fab")
			(hide yes)
			(effects
				(font
					(size 1 1)
					(thickness 0.15)
				)
			)
		)
		(property "Val" "200k"
			(at 0 0 270)
			(unlocked yes)
			(layer "F.Fab")
			(hide yes)
			(effects
				(font
					(size 1 1)
					(thickness 0.15)
				)
			)
		)
		(property "Tolerance" "1%"
			(at 0 0 270)
			(unlocked yes)
			(layer "F.Fab")
			(hide yes)
			(effects
				(font
					(size 1 1)
					(thickness 0.15)
				)
			)
		)
		(sheetname "/DCDC/")
		(sheetfile "dcdc.kicad_sch")
		(attr smd)
		(fp_rect
			(start -0.925 -0.47)
			(end 0.925 0.47)
			(stroke
				(width 0.05)
				(type default)
			)
			(fill no)
			(layer "F.CrtYd")
		)
		(fp_rect
			(start -0.5 -0.25)
			(end 0.5 0.25)
			(stroke
				(width 0.15)
				(type solid)
			)
			(fill no)
			(layer "F.Fab")
		)
		(fp_text user "License: Apache-2.0"
			(at -0.95 5.169 90)
			(layer "F.Fab")
			(effects
				(font
					(size 0.7 0.7)
					(thickness 0.15)
				)
				(justify right top)
			)
		)
		(fp_text user "Author: Antmicro"
			(at -0.95 4.169 90)
			(layer "F.Fab")
			(effects
				(font
					(size 0.7 0.7)
					(thickness 0.15)
				)
				(justify right top)
			)
		)
		(fp_text user "${REFERENCE}"
			(at -0.95 3.168 90)
			(layer "F.Fab")
			(effects
				(font
					(size 0.7 0.7)
					(thickness 0.15)
				)
				(justify right top)
			)
		)
		(pad "1" smd roundrect
			(at -0.48 0 270)
			(size 0.59 0.64)
			(layers "F.Cu" "F.Mask" "F.Paste")
			(roundrect_rratio 0.25)
			(net 1 "GND")
			(pintype "passive")
		)
		(pad "2" smd roundrect
			(at 0.48 0 270)
			(size 0.59 0.64)
			(layers "F.Cu" "F.Mask" "F.Paste")
			(roundrect_rratio 0.25)
			(net 1216 "/DCDC/3V3_MODE2")
			(pintype "passive")
		)
	)
	(footprint "antmicro-footprints:C_0402_1005Metric"
		(layer "F.Cu")
		(at 89.55 146.411499 -90)
		(descr "Capacitor SMD 0402")
		(tags "capacitor SMD 0402")
		(property "Reference" "C11"
			(at -3.05 0.33 90)
			(layer "F.SilkS")
			(effects
				(font
					(size 0.7 0.7)
					(thickness 0.15)
				)
				(justify right top)
			)
		)
		(property "Value" "C_100n_0402"
			(at -1.022927 2.155213 90)
			(layer "F.Fab")
			(effects
				(font
					(size 0.7 0.7)
					(thickness 0.15)
				)
				(justify right top)
			)
		)
		(property "Datasheet" "https://www.murata.com/products/productdetail?partno=GRM155R61H104KE14%23"
			(at 0 0 90)
			(layer "F.Fab")
			(hide yes)
			(effects
				(font
					(size 1.27 1.27)
					(thickness 0.15)
				)
			)
		)
		(property "Description" "SMD Multilayer Ceramic Capacitor, 0.1 µF, 50 V, 0402 [1005 Metric], ± 10%, X5R, GRM Series"
			(at 0 0 90)
			(layer "F.Fab")
			(hide yes)
			(effects
				(font
					(size 1.27 1.27)
					(thickness 0.15)
				)
			)
		)
		(property "MPN" "GRM155R61H104KE14D"
			(at 0 0 270)
			(unlocked yes)
			(layer "F.Fab")
			(hide yes)
			(effects
				(font
					(size 1 1)
					(thickness 0.15)
				)
			)
		)
		(property "Manufacturer" "Murata"
			(at 0 0 270)
			(unlocked yes)
			(layer "F.Fab")
			(hide yes)
			(effects
				(font
					(size 1 1)
					(thickness 0.15)
				)
			)
		)
		(property "License" "Apache-2.0"
			(at 0 0 270)
			(unlocked yes)
			(layer "F.Fab")
			(hide yes)
			(effects
				(font
					(size 1 1)
					(thickness 0.15)
				)
			)
		)
		(property "Author" "Antmicro"
			(at 0 0 270)
			(unlocked yes)
			(layer "F.Fab")
			(hide yes)
			(effects
				(font
					(size 1 1)
					(thickness 0.15)
				)
			)
		)
		(property "Val" "100n"
			(at 0 0 270)
			(unlocked yes)
			(layer "F.Fab")
			(hide yes)
			(effects
				(font
					(size 1 1)
					(thickness 0.15)
				)
			)
		)
		(property "Voltage" "50V"
			(at 0 0 270)
			(unlocked yes)
			(layer "F.Fab")
			(hide yes)
			(effects
				(font
					(size 1 1)
					(thickness 0.15)
				)
			)
		)
		(property "Dielectric" "X5R"
			(at 0 0 270)
			(unlocked yes)
			(layer "F.Fab")
			(hide yes)
			(effects
				(font
					(size 1 1)
					(thickness 0.15)
				)
			)
		)
		(sheetname "/SoM_IO2/")
		(sheetfile "som_io2.kicad_sch")
		(attr smd)
		(fp_poly
			(pts
				(xy -0.925 -0.47) (xy -0.925 0.47) (xy 0.925 0.47) (xy 0.925 -0.47)
			)
			(stroke
				(width 0.05)
				(type default)
			)
			(fill no)
			(layer "F.CrtYd")
		)
		(fp_line
			(start -0.494 0.248)
			(end -0.494 -0.25)
			(stroke
				(width 0.15)
				(type solid)
			)
			(layer "F.Fab")
		)
		(fp_line
			(start 0.504 0.248)
			(end -0.494 0.248)
			(stroke
				(width 0.15)
				(type solid)
			)
			(layer "F.Fab")
		)
		(fp_line
			(start -0.494 -0.25)
			(end 0.504 -0.25)
			(stroke
				(width 0.15)
				(type solid)
			)
			(layer "F.Fab")
		)
		(fp_line
			(start 0.504 -0.25)
			(end 0.504 0.248)
			(stroke
				(width 0.15)
				(type solid)
			)
			(layer "F.Fab")
		)
		(fp_text user "Author: Antmicro"
			(at -0.939 3.399 90)
			(layer "F.Fab")
			(effects
				(font
					(size 0.7 0.7)
					(thickness 0.15)
				)
				(justify right top)
			)
		)
		(fp_text user "${REFERENCE}"
			(at -0.939 4.599 90)
			(layer "F.Fab")
			(effects
				(font
					(size 0.7 0.7)
					(thickness 0.15)
				)
				(justify right top)
			)
		)
		(fp_text user "License: Apache-2.0"
			(at -0.939 5.799 90)
			(layer "F.Fab")
			(effects
				(font
					(size 0.7 0.7)
					(thickness 0.15)
				)
				(justify right top)
			)
		)
		(pad "1" smd roundrect
			(at -0.48 0 270)
			(size 0.59 0.64)
			(layers "F.Cu" "F.Mask" "F.Paste")
			(roundrect_rratio 0.25)
			(net 1 "GND")
			(pintype "passive")
		)
		(pad "2" smd roundrect
			(at 0.48 0 270)
			(size 0.59 0.64)
			(layers "F.Cu" "F.Mask" "F.Paste")
			(roundrect_rratio 0.25)
			(net 2 "+3V3")
			(pintype "passive")
		)
	)
)
